(kicad_pcb
	(version 20260206)
	(generator "pcbnew")
	(generator_version "10.0")
	(general
		(thickness 1.6)
		(legacy_teardrops no)
	)
	(paper "A4")
	(title_block
		(title "01162023_DA0F0TEBIF0_F0T_Expander_BD_F_brd_V02_OCP.brd")
		(comment 1 "Grand Teton / footprints 2465-2471 of 9728")
	)
	(layers
		(0 "F.Cu" signal "TOP")
		(4 "In1.Cu" signal "GND")
		(6 "In2.Cu" signal "VCC")
		(8 "In3.Cu" signal "VCC1")
		(10 "In4.Cu" signal "GND1")
		(12 "In5.Cu" signal "IN1")
		(14 "In6.Cu" signal "GND2")
		(16 "In7.Cu" signal "IN2")
		(18 "In8.Cu" signal "GND3")
		(20 "In9.Cu" signal "IN3")
		(22 "In10.Cu" signal "GND4")
		(24 "In11.Cu" signal "IN4")
		(26 "In12.Cu" signal "GND5")
		(28 "In13.Cu" signal "IN5")
		(30 "In14.Cu" signal "GND6")
		(32 "In15.Cu" signal "IN6")
		(34 "In16.Cu" signal "GND7")
		(2 "B.Cu" signal "BOTTOM")
		(9 "F.Adhes" user "F.Adhesive")
		(11 "B.Adhes" user "B.Adhesive")
		(13 "F.Paste" user "Package Geometry/Pastemask Top")
		(15 "B.Paste" user "Package Geometry/Pastemask Bottom")
		(5 "F.SilkS" user "Ref Des/Silkscreen Top")
		(7 "B.SilkS" user "Ref Des/Silkscreen Bottom")
		(1 "F.Mask" user "Board Geometry/Soldermask Top")
		(3 "B.Mask" user "Board Geometry/Soldermask Bottom")
		(17 "Dwgs.User" user "User.Drawings")
		(19 "Cmts.User" user "User.Comments")
		(21 "Eco1.User" user "User.Eco1")
		(23 "Eco2.User" user "User.Eco2")
		(25 "Edge.Cuts" user "Board Geometry/Outline")
		(27 "Margin" user)
		(31 "F.CrtYd" user "Package Geometry/Place Bound Top")
		(29 "B.CrtYd" user "Package Geometry/Place Bound Bottom")
		(35 "F.Fab" user "Ref Des/Assembly Top")
		(33 "B.Fab" user "Ref Des/Assembly Bottom")
	)
	(footprint ""
		(layer "F.Cu")
		(at 58.177176 -374.528588 180)
		(property "Reference" "C4009"
			(at 0 0 180)
			(layer "F.SilkS")
			(hide yes)
			(effects
				(font
					(size 1.27 1.27)
				)
			)
		)
		(property "Value" ""
			(at 0 0 180)
			(layer "F.Fab")
			(effects
				(font
					(size 1.27 1.27)
				)
			)
		)
		(duplicate_pad_numbers_are_jumpers no)
		(fp_line
			(start 0.7874 0.4064)
			(end -0.7874 0.4064)
			(stroke
				(width 0.1524)
				(type default)
			)
			(layer "F.SilkS")
		)
		(fp_line
			(start 0.7874 -0.4064)
			(end 0.7874 0.4064)
			(stroke
				(width 0.1524)
				(type default)
			)
			(layer "F.SilkS")
		)
		(fp_line
			(start -0.7874 0.4064)
			(end -0.7874 -0.4064)
			(stroke
				(width 0.1524)
				(type default)
			)
			(layer "F.SilkS")
		)
		(fp_line
			(start -0.7874 -0.4064)
			(end 0.7874 -0.4064)
			(stroke
				(width 0.1524)
				(type default)
			)
			(layer "F.SilkS")
		)
		(fp_line
			(start 0.67945 0.3048)
			(end 0.120396 0.3048)
			(stroke
				(width 0.1)
				(type default)
			)
			(layer "F.Fab")
		)
		(fp_line
			(start 0.67945 -0.3048)
			(end 0.67945 0.3048)
			(stroke
				(width 0.1)
				(type default)
			)
			(layer "F.Fab")
		)
		(fp_line
			(start 0.12065 -0.2794)
			(end 0.12065 -0.3048)
			(stroke
				(width 0.1)
				(type default)
			)
			(layer "F.Fab")
		)
		(fp_line
			(start 0.12065 -0.3048)
			(end 0.67945 -0.3048)
			(stroke
				(width 0.1)
				(type default)
			)
			(layer "F.Fab")
		)
		(fp_line
			(start 0.120396 0.3048)
			(end 0.120396 0.2794)
			(stroke
				(width 0.1)
				(type default)
			)
			(layer "F.Fab")
		)
		(fp_line
			(start 0.120396 0.2794)
			(end -0.12065 0.2794)
			(stroke
				(width 0.1)
				(type default)
			)
			(layer "F.Fab")
		)
		(fp_line
			(start -0.12065 0.3048)
			(end -0.67945 0.3048)
			(stroke
				(width 0.1)
				(type default)
			)
			(layer "F.Fab")
		)
		(fp_line
			(start -0.12065 0.2794)
			(end -0.12065 0.3048)
			(stroke
				(width 0.1)
				(type default)
			)
			(layer "F.Fab")
		)
		(fp_line
			(start -0.12065 -0.2794)
			(end 0.12065 -0.2794)
			(stroke
				(width 0.1)
				(type default)
			)
			(layer "F.Fab")
		)
		(fp_line
			(start -0.12065 -0.305054)
			(end -0.12065 -0.2794)
			(stroke
				(width 0.1)
				(type default)
			)
			(layer "F.Fab")
		)
		(fp_line
			(start -0.67945 0.3048)
			(end -0.67945 -0.305054)
			(stroke
				(width 0.1)
				(type default)
			)
			(layer "F.Fab")
		)
		(fp_line
			(start -0.67945 -0.305054)
			(end -0.12065 -0.305054)
			(stroke
				(width 0.1)
				(type default)
			)
			(layer "F.Fab")
		)
		(pad "1" smd circle
			(at -0.40005 0 180)
			(size 0 0)
			(layers "F.Cu" "F.Mask" "F.Paste")
			(net "GND")
		)
		(pad "2" smd circle
			(at 0.40005 0 180)
			(size 0 0)
			(layers "F.Cu" "F.Mask" "F.Paste")
			(net "PRSNT_GPU_D_N")
		)
	)
	(footprint ""
		(layer "F.Cu")
		(at 155.380436 -121.005346)
		(property "Reference" "C256"
			(at 0 0 0)
			(layer "F.SilkS")
			(hide yes)
			(effects
				(font
					(size 1.27 1.27)
				)
			)
		)
		(property "Value" ""
			(at 0 0 0)
			(layer "F.Fab")
			(effects
				(font
					(size 1.27 1.27)
				)
			)
		)
		(duplicate_pad_numbers_are_jumpers no)
		(fp_line
			(start -0.299974 -0.150114)
			(end 0.299974 -0.150114)
			(stroke
				(width 0.1)
				(type default)
			)
			(layer "F.Fab")
		)
		(fp_line
			(start -0.299974 0.150114)
			(end -0.299974 -0.150114)
			(stroke
				(width 0.1)
				(type default)
			)
			(layer "F.Fab")
		)
		(fp_line
			(start 0.299974 -0.150114)
			(end 0.299974 0.150114)
			(stroke
				(width 0.1)
				(type default)
			)
			(layer "F.Fab")
		)
		(fp_line
			(start 0.299974 0.150114)
			(end -0.299974 0.150114)
			(stroke
				(width 0.1)
				(type default)
			)
			(layer "F.Fab")
		)
		(pad "1" smd rect
			(at -0.2667 0)
			(size 0.3048 0.381)
			(layers "F.Cu" "F.Mask" "F.Paste")
			(net "P5E_PEX1_STN1_TX_DN<25>")
		)
		(pad "2" smd rect
			(at 0.2667 0)
			(size 0.3048 0.381)
			(layers "F.Cu" "F.Mask" "F.Paste")
			(net "P5E_PEX1_STN1_TX_C_DN<25>")
		)
	)
	(footprint ""
		(layer "F.Cu")
		(at 232.092754 -254.43942 -90)
		(property "Reference" "C4339"
			(at 0 0 270)
			(layer "F.SilkS")
			(hide yes)
			(effects
				(font
					(size 1.27 1.27)
				)
			)
		)
		(property "Value" ""
			(at 0 0 270)
			(layer "F.Fab")
			(effects
				(font
					(size 1.27 1.27)
				)
			)
		)
		(duplicate_pad_numbers_are_jumpers no)
		(fp_line
			(start -1.2954 0.5842)
			(end -1.2954 -0.5842)
			(stroke
				(width 0.1524)
				(type default)
			)
			(layer "F.SilkS")
		)
		(fp_line
			(start 1.2954 0.5842)
			(end -1.2954 0.5842)
			(stroke
				(width 0.1524)
				(type default)
			)
			(layer "F.SilkS")
		)
		(fp_line
			(start -1.2954 -0.5842)
			(end 1.2954 -0.5842)
			(stroke
				(width 0.1524)
				(type default)
			)
			(layer "F.SilkS")
		)
		(fp_line
			(start 1.2954 -0.5842)
			(end 1.2954 0.5842)
			(stroke
				(width 0.1524)
				(type default)
			)
			(layer "F.SilkS")
		)
		(fp_line
			(start -0.8636 0.4572)
			(end -0.8636 0.4064)
			(stroke
				(width 0.1)
				(type default)
			)
			(layer "F.Fab")
		)
		(fp_line
			(start 0.8636 0.4572)
			(end -0.8636 0.4572)
			(stroke
				(width 0.1)
				(type default)
			)
			(layer "F.Fab")
		)
		(fp_line
			(start -1.1938 0.4064)
			(end -1.1938 -0.4064)
			(stroke
				(width 0.1)
				(type default)
			)
			(layer "F.Fab")
		)
		(fp_line
			(start -0.8636 0.4064)
			(end -1.1938 0.4064)
			(stroke
				(width 0.1)
				(type default)
			)
			(layer "F.Fab")
		)
		(fp_line
			(start 0.8636 0.4064)
			(end 0.8636 0.4572)
			(stroke
				(width 0.1)
				(type default)
			)
			(layer "F.Fab")
		)
		(fp_line
			(start 1.1938 0.4064)
			(end 0.8636 0.4064)
			(stroke
				(width 0.1)
				(type default)
			)
			(layer "F.Fab")
		)
		(fp_line
			(start -1.1938 -0.4064)
			(end -0.8636 -0.4064)
			(stroke
				(width 0.1)
				(type default)
			)
			(layer "F.Fab")
		)
		(fp_line
			(start -0.8636 -0.4064)
			(end -0.8636 -0.4572)
			(stroke
				(width 0.1)
				(type default)
			)
			(layer "F.Fab")
		)
		(fp_line
			(start 0.8636 -0.4064)
			(end 1.1938 -0.4064)
			(stroke
				(width 0.1)
				(type default)
			)
			(layer "F.Fab")
		)
		(fp_line
			(start 1.1938 -0.4064)
			(end 1.1938 0.4064)
			(stroke
				(width 0.1)
				(type default)
			)
			(layer "F.Fab")
		)
		(fp_line
			(start -0.8636 -0.4572)
			(end 0.8636 -0.4572)
			(stroke
				(width 0.1)
				(type default)
			)
			(layer "F.Fab")
		)
		(fp_line
			(start 0.8636 -0.4572)
			(end 0.8636 -0.4064)
			(stroke
				(width 0.1)
				(type default)
			)
			(layer "F.Fab")
		)
		(pad "1" smd rect
			(at -0.7366 0 180)
			(size 0.7112 0.8128)
			(layers "F.Cu" "F.Mask" "F.Paste")
			(net "P1V25_SERDES_VDDPLL_PEX2_C1")
		)
		(pad "2" smd rect
			(at 0.7366 0 180)
			(size 0.7112 0.8128)
			(layers "F.Cu" "F.Mask" "F.Paste")
			(net "GND")
		)
	)
	(footprint ""
		(layer "F.Cu")
		(at 136.445244 -91.242642 180)
		(property "Reference" "R1582"
			(at 0 0 180)
			(layer "F.SilkS")
			(hide yes)
			(effects
				(font
					(size 1.27 1.27)
				)
			)
		)
		(property "Value" ""
			(at 0 0 180)
			(layer "F.Fab")
			(effects
				(font
					(size 1.27 1.27)
				)
			)
		)
		(duplicate_pad_numbers_are_jumpers no)
		(fp_line
			(start 0.7874 0.4064)
			(end -0.7874 0.4064)
			(stroke
				(width 0.1524)
				(type default)
			)
			(layer "F.SilkS")
		)
		(fp_line
			(start 0.7874 -0.4064)
			(end 0.7874 0.4064)
			(stroke
				(width 0.1524)
				(type default)
			)
			(layer "F.SilkS")
		)
		(fp_line
			(start -0.7874 0.4064)
			(end -0.7874 -0.4064)
			(stroke
				(width 0.1524)
				(type default)
			)
			(layer "F.SilkS")
		)
		(fp_line
			(start -0.7874 -0.4064)
			(end 0.7874 -0.4064)
			(stroke
				(width 0.1524)
				(type default)
			)
			(layer "F.SilkS")
		)
		(fp_line
			(start 0.67945 0.3048)
			(end 0.120396 0.3048)
			(stroke
				(width 0.1)
				(type default)
			)
			(layer "F.Fab")
		)
		(fp_line
			(start 0.67945 -0.3048)
			(end 0.67945 0.3048)
			(stroke
				(width 0.1)
				(type default)
			)
			(layer "F.Fab")
		)
		(fp_line
			(start 0.12065 -0.2794)
			(end 0.12065 -0.3048)
			(stroke
				(width 0.1)
				(type default)
			)
			(layer "F.Fab")
		)
		(fp_line
			(start 0.12065 -0.3048)
			(end 0.67945 -0.3048)
			(stroke
				(width 0.1)
				(type default)
			)
			(layer "F.Fab")
		)
		(fp_line
			(start 0.120396 0.3048)
			(end 0.120396 0.2794)
			(stroke
				(width 0.1)
				(type default)
			)
			(layer "F.Fab")
		)
		(fp_line
			(start 0.120396 0.2794)
			(end -0.12065 0.2794)
			(stroke
				(width 0.1)
				(type default)
			)
			(layer "F.Fab")
		)
		(fp_line
			(start -0.12065 0.3048)
			(end -0.67945 0.3048)
			(stroke
				(width 0.1)
				(type default)
			)
			(layer "F.Fab")
		)
		(fp_line
			(start -0.12065 0.2794)
			(end -0.12065 0.3048)
			(stroke
				(width 0.1)
				(type default)
			)
			(layer "F.Fab")
		)
		(fp_line
			(start -0.12065 -0.2794)
			(end 0.12065 -0.2794)
			(stroke
				(width 0.1)
				(type default)
			)
			(layer "F.Fab")
		)
		(fp_line
			(start -0.12065 -0.305054)
			(end -0.12065 -0.2794)
			(stroke
				(width 0.1)
				(type default)
			)
			(layer "F.Fab")
		)
		(fp_line
			(start -0.67945 0.3048)
			(end -0.67945 -0.305054)
			(stroke
				(width 0.1)
				(type default)
			)
			(layer "F.Fab")
		)
		(fp_line
			(start -0.67945 -0.305054)
			(end -0.12065 -0.305054)
			(stroke
				(width 0.1)
				(type default)
			)
			(layer "F.Fab")
		)
		(pad "1" smd circle
			(at -0.40005 0 180)
			(size 0 0)
			(layers "F.Cu" "F.Mask" "F.Paste")
			(net "SMB_BIC_I2C9_MUX0_SSD5_R_SCL")
		)
		(pad "2" smd circle
			(at 0.40005 0 180)
			(size 0 0)
			(layers "F.Cu" "F.Mask" "F.Paste")
			(net "SMB_BIC_I2C9_MUX0_SSD5_SCL")
		)
	)
	(footprint ""
		(layer "F.Cu")
		(at 220.125036 -14.735302 180)
		(property "Reference" "C2726"
			(at 0 0 180)
			(layer "F.SilkS")
			(hide yes)
			(effects
				(font
					(size 1.27 1.27)
				)
			)
		)
		(property "Value" ""
			(at 0 0 180)
			(layer "F.Fab")
			(effects
				(font
					(size 1.27 1.27)
				)
			)
		)
		(duplicate_pad_numbers_are_jumpers no)
		(fp_line
			(start 0.7874 0.4064)
			(end -0.7874 0.4064)
			(stroke
				(width 0.1524)
				(type default)
			)
			(layer "F.SilkS")
		)
		(fp_line
			(start 0.7874 -0.4064)
			(end 0.7874 0.4064)
			(stroke
				(width 0.1524)
				(type default)
			)
			(layer "F.SilkS")
		)
		(fp_line
			(start -0.7874 0.4064)
			(end -0.7874 -0.4064)
			(stroke
				(width 0.1524)
				(type default)
			)
			(layer "F.SilkS")
		)
		(fp_line
			(start -0.7874 -0.4064)
			(end 0.7874 -0.4064)
			(stroke
				(width 0.1524)
				(type default)
			)
			(layer "F.SilkS")
		)
		(fp_line
			(start 0.67945 0.3048)
			(end 0.120396 0.3048)
			(stroke
				(width 0.1)
				(type default)
			)
			(layer "F.Fab")
		)
		(fp_line
			(start 0.67945 -0.3048)
			(end 0.67945 0.3048)
			(stroke
				(width 0.1)
				(type default)
			)
			(layer "F.Fab")
		)
		(fp_line
			(start 0.12065 -0.2794)
			(end 0.12065 -0.3048)
			(stroke
				(width 0.1)
				(type default)
			)
			(layer "F.Fab")
		)
		(fp_line
			(start 0.12065 -0.3048)
			(end 0.67945 -0.3048)
			(stroke
				(width 0.1)
				(type default)
			)
			(layer "F.Fab")
		)
		(fp_line
			(start 0.120396 0.3048)
			(end 0.120396 0.2794)
			(stroke
				(width 0.1)
				(type default)
			)
			(layer "F.Fab")
		)
		(fp_line
			(start 0.120396 0.2794)
			(end -0.12065 0.2794)
			(stroke
				(width 0.1)
				(type default)
			)
			(layer "F.Fab")
		)
		(fp_line
			(start -0.12065 0.3048)
			(end -0.67945 0.3048)
			(stroke
				(width 0.1)
				(type default)
			)
			(layer "F.Fab")
		)
		(fp_line
			(start -0.12065 0.2794)
			(end -0.12065 0.3048)
			(stroke
				(width 0.1)
				(type default)
			)
			(layer "F.Fab")
		)
		(fp_line
			(start -0.12065 -0.2794)
			(end 0.12065 -0.2794)
			(stroke
				(width 0.1)
				(type default)
			)
			(layer "F.Fab")
		)
		(fp_line
			(start -0.12065 -0.305054)
			(end -0.12065 -0.2794)
			(stroke
				(width 0.1)
				(type default)
			)
			(layer "F.Fab")
		)
		(fp_line
			(start -0.67945 0.3048)
			(end -0.67945 -0.305054)
			(stroke
				(width 0.1)
				(type default)
			)
			(layer "F.Fab")
		)
		(fp_line
			(start -0.67945 -0.305054)
			(end -0.12065 -0.305054)
			(stroke
				(width 0.1)
				(type default)
			)
			(layer "F.Fab")
		)
		(pad "1" smd circle
			(at -0.40005 0 180)
			(size 0 0)
			(layers "F.Cu" "F.Mask" "F.Paste")
			(net "GND")
		)
		(pad "2" smd circle
			(at 0.40005 0 180)
			(size 0 0)
			(layers "F.Cu" "F.Mask" "F.Paste")
			(net "P3V3_SSD7")
		)
	)
	(footprint ""
		(layer "F.Cu")
		(at 58.686192 -386.734812)
		(property "Reference" "R1830"
			(at 0 0 0)
			(layer "F.SilkS")
			(hide yes)
			(effects
				(font
					(size 1.27 1.27)
				)
			)
		)
		(property "Value" ""
			(at 0 0 0)
			(layer "F.Fab")
			(effects
				(font
					(size 1.27 1.27)
				)
			)
		)
		(duplicate_pad_numbers_are_jumpers no)
		(fp_line
			(start -0.7874 -0.4064)
			(end 0.7874 -0.4064)
			(stroke
				(width 0.1524)
				(type default)
			)
			(layer "F.SilkS")
		)
		(fp_line
			(start -0.7874 0.4064)
			(end -0.7874 -0.4064)
			(stroke
				(width 0.1524)
				(type default)
			)
			(layer "F.SilkS")
		)
		(fp_line
			(start 0.7874 -0.4064)
			(end 0.7874 0.4064)
			(stroke
				(width 0.1524)
				(type default)
			)
			(layer "F.SilkS")
		)
		(fp_line
			(start 0.7874 0.4064)
			(end -0.7874 0.4064)
			(stroke
				(width 0.1524)
				(type default)
			)
			(layer "F.SilkS")
		)
		(fp_line
			(start -0.67945 -0.305054)
			(end -0.12065 -0.305054)
			(stroke
				(width 0.1)
				(type default)
			)
			(layer "F.Fab")
		)
		(fp_line
			(start -0.67945 0.3048)
			(end -0.67945 -0.305054)
			(stroke
				(width 0.1)
				(type default)
			)
			(layer "F.Fab")
		)
		(fp_line
			(start -0.12065 -0.305054)
			(end -0.12065 -0.2794)
			(stroke
				(width 0.1)
				(type default)
			)
			(layer "F.Fab")
		)
		(fp_line
			(start -0.12065 -0.2794)
			(end 0.12065 -0.2794)
			(stroke
				(width 0.1)
				(type default)
			)
			(layer "F.Fab")
		)
		(fp_line
			(start -0.12065 0.2794)
			(end -0.12065 0.3048)
			(stroke
				(width 0.1)
				(type default)
			)
			(layer "F.Fab")
		)
		(fp_line
			(start -0.12065 0.3048)
			(end -0.67945 0.3048)
			(stroke
				(width 0.1)
				(type default)
			)
			(layer "F.Fab")
		)
		(fp_line
			(start 0.120396 0.2794)
			(end -0.12065 0.2794)
			(stroke
				(width 0.1)
				(type default)
			)
			(layer "F.Fab")
		)
		(fp_line
			(start 0.120396 0.3048)
			(end 0.120396 0.2794)
			(stroke
				(width 0.1)
				(type default)
			)
			(layer "F.Fab")
		)
		(fp_line
			(start 0.12065 -0.3048)
			(end 0.67945 -0.3048)
			(stroke
				(width 0.1)
				(type default)
			)
			(layer "F.Fab")
		)
		(fp_line
			(start 0.12065 -0.2794)
			(end 0.12065 -0.3048)
			(stroke
				(width 0.1)
				(type default)
			)
			(layer "F.Fab")
		)
		(fp_line
			(start 0.67945 -0.3048)
			(end 0.67945 0.3048)
			(stroke
				(width 0.1)
				(type default)
			)
			(layer "F.Fab")
		)
		(fp_line
			(start 0.67945 0.3048)
			(end 0.120396 0.3048)
			(stroke
				(width 0.1)
				(type default)
			)
			(layer "F.Fab")
		)
		(pad "1" smd circle
			(at -0.40005 0)
			(size 0 0)
			(layers "F.Cu" "F.Mask" "F.Paste")
			(net "GPU_BASE_ID0_R")
		)
		(pad "2" smd circle
			(at 0.40005 0)
			(size 0 0)
			(layers "F.Cu" "F.Mask" "F.Paste")
			(net "GPU_BASE_ID0")
		)
	)
	(footprint ""
		(layer "F.Cu")
		(at 359.156 -173.99)
		(property "Reference" "R4664"
			(at 0 0 0)
			(layer "F.SilkS")
			(hide yes)
			(effects
				(font
					(size 1.27 1.27)
				)
			)
		)
		(property "Value" ""
			(at 0 0 0)
			(layer "F.Fab")
			(effects
				(font
					(size 1.27 1.27)
				)
			)
		)
		(duplicate_pad_numbers_are_jumpers no)
		(fp_line
			(start -0.7874 -0.4064)
			(end 0.7874 -0.4064)
			(stroke
				(width 0.1524)
				(type default)
			)
			(layer "F.SilkS")
		)
		(fp_line
			(start -0.7874 0.4064)
			(end -0.7874 -0.4064)
			(stroke
				(width 0.1524)
				(type default)
			)
			(layer "F.SilkS")
		)
		(fp_line
			(start 0.7874 -0.4064)
			(end 0.7874 0.4064)
			(stroke
				(width 0.1524)
				(type default)
			)
			(layer "F.SilkS")
		)
		(fp_line
			(start 0.7874 0.4064)
			(end -0.7874 0.4064)
			(stroke
				(width 0.1524)
				(type default)
			)
			(layer "F.SilkS")
		)
		(fp_line
			(start -0.67945 -0.305054)
			(end -0.12065 -0.305054)
			(stroke
				(width 0.1)
				(type default)
			)
			(layer "F.Fab")
		)
		(fp_line
			(start -0.67945 0.3048)
			(end -0.67945 -0.305054)
			(stroke
				(width 0.1)
				(type default)
			)
			(layer "F.Fab")
		)
		(fp_line
			(start -0.12065 -0.305054)
			(end -0.12065 -0.2794)
			(stroke
				(width 0.1)
				(type default)
			)
			(layer "F.Fab")
		)
		(fp_line
			(start -0.12065 -0.2794)
			(end 0.12065 -0.2794)
			(stroke
				(width 0.1)
				(type default)
			)
			(layer "F.Fab")
		)
		(fp_line
			(start -0.12065 0.2794)
			(end -0.12065 0.3048)
			(stroke
				(width 0.1)
				(type default)
			)
			(layer "F.Fab")
		)
		(fp_line
			(start -0.12065 0.3048)
			(end -0.67945 0.3048)
			(stroke
				(width 0.1)
				(type default)
			)
			(layer "F.Fab")
		)
		(fp_line
			(start 0.120396 0.2794)
			(end -0.12065 0.2794)
			(stroke
				(width 0.1)
				(type default)
			)
			(layer "F.Fab")
		)
		(fp_line
			(start 0.120396 0.3048)
			(end 0.120396 0.2794)
			(stroke
				(width 0.1)
				(type default)
			)
			(layer "F.Fab")
		)
		(fp_line
			(start 0.12065 -0.3048)
			(end 0.67945 -0.3048)
			(stroke
				(width 0.1)
				(type default)
			)
			(layer "F.Fab")
		)
		(fp_line
			(start 0.12065 -0.2794)
			(end 0.12065 -0.3048)
			(stroke
				(width 0.1)
				(type default)
			)
			(layer "F.Fab")
		)
		(fp_line
			(start 0.67945 -0.3048)
			(end 0.67945 0.3048)
			(stroke
				(width 0.1)
				(type default)
			)
			(layer "F.Fab")
		)
		(fp_line
			(start 0.67945 0.3048)
			(end 0.120396 0.3048)
			(stroke
				(width 0.1)
				(type default)
			)
			(layer "F.Fab")
		)
		(pad "1" smd circle
			(at -0.40005 0)
			(size 0 0)
			(layers "F.Cu" "F.Mask" "F.Paste")
			(net "P3V3_AUX")
		)
		(pad "2" smd circle
			(at 0.40005 0)
			(size 0 0)
			(layers "F.Cu" "F.Mask" "F.Paste")
			(net "SSD7_PEX_PWR_EN_R")
		)
	)
)
